(kicad_pcb
	(version 20260206)
	(generator "pcbnew")
	(generator_version "10.0")
	(general
		(thickness 1.6)
		(legacy_teardrops no)
	)
	(paper "A4")
	(title_block
		(title "v2-tray-backplane — ms_tbp_v2.brd")
		(comment 1 "Open CloudServer (Microsoft) / footprints 18-27 of 164")
	)
	(layers
		(0 "F.Cu" signal "TOP")
		(4 "In1.Cu" signal "LYR2")
		(6 "In2.Cu" signal "LYR3")
		(8 "In3.Cu" signal "LYR4")
		(10 "In4.Cu" signal "LYR5")
		(12 "In5.Cu" signal "LYR6")
		(14 "In6.Cu" signal "LYR7")
		(2 "B.Cu" signal "BOTTOM")
		(9 "F.Adhes" user "F.Adhesive")
		(11 "B.Adhes" user "B.Adhesive")
		(13 "F.Paste" user "Package Geometry/Pastemask Top")
		(15 "B.Paste" user "Package Geometry/Pastemask Bottom")
		(5 "F.SilkS" user "Ref Des/Silkscreen Top")
		(7 "B.SilkS" user "Ref Des/Silkscreen Bottom")
		(1 "F.Mask" user "Board Geometry/Soldermask Top")
		(3 "B.Mask" user "Board Geometry/Soldermask Bottom")
		(17 "Dwgs.User" user "User.Drawings")
		(19 "Cmts.User" user "User.Comments")
		(21 "Eco1.User" user "User.Eco1")
		(23 "Eco2.User" user "User.Eco2")
		(25 "Edge.Cuts" user "Board Geometry/Outline")
		(27 "Margin" user)
		(31 "F.CrtYd" user "Package Geometry/Place Bound Top")
		(29 "B.CrtYd" user "Package Geometry/Place Bound Bottom")
		(35 "F.Fab" user "Ref Des/Assembly Top")
		(33 "B.Fab" user "Ref Des/Assembly Bottom")
	)
	(footprint ""
		(layer "F.Cu")
		(at -110.8456 9.0424)
		(property "Reference" "R62"
			(at 2.8956 0.0127 0)
			(unlocked yes)
			(layer "F.SilkS")
			(effects
				(font
					(size 0.762 0.5334)
					(thickness 0.1016)
				)
			)
		)
		(property "Value" ""
			(at 0 0 0)
			(layer "F.Fab")
			(effects
				(font
					(size 1.27 1.27)
				)
			)
		)
		(duplicate_pad_numbers_are_jumpers no)
		(fp_line
			(start 0 -0.381)
			(end 0 0.381)
			(stroke
				(width 0.127)
				(type default)
			)
			(layer "F.SilkS")
		)
		(fp_poly
			(pts
				(xy 1.255601 0.6564) (xy -1.255601 0.6564) (xy -1.255601 -0.656399) (xy 1.255601 -0.656399)
			)
			(stroke
				(width 0)
				(type default)
			)
			(fill no)
			(layer "F.CrtYd")
		)
		(fp_line
			(start -0.800001 -0.399999)
			(end -0.800001 0.399999)
			(stroke
				(width 0.1)
				(type default)
			)
			(layer "F.Fab")
		)
		(fp_line
			(start -0.800001 0.399999)
			(end 0.800001 0.399999)
			(stroke
				(width 0.1)
				(type default)
			)
			(layer "F.Fab")
		)
		(fp_line
			(start 0.800001 -0.399999)
			(end -0.800001 -0.399999)
			(stroke
				(width 0.1)
				(type default)
			)
			(layer "F.Fab")
		)
		(fp_line
			(start 0.800001 0.399999)
			(end 0.800001 -0.399999)
			(stroke
				(width 0.1)
				(type default)
			)
			(layer "F.Fab")
		)
		(pad "1" smd rect
			(at -0.650001 0)
			(size 0.7112 0.8128)
			(layers "F.Cu" "F.Mask" "F.Paste")
			(net "P3V3_B2_QSFP")
		)
		(pad "2" smd rect
			(at 0.650001 0 180)
			(size 0.7112 0.8128)
			(layers "F.Cu" "F.Mask" "F.Paste")
			(net "ETH40G_B2_MODSEL_N")
		)
	)
	(footprint ""
		(layer "F.Cu")
		(at -266.4714 5.842)
		(property "Reference" "FS8"
			(at 2.3114 0.1651 0)
			(unlocked yes)
			(layer "F.SilkS")
			(effects
				(font
					(size 0.762 0.5334)
					(thickness 0.1016)
				)
			)
		)
		(property "Value" ""
			(at 0 0 0)
			(layer "F.Fab")
			(effects
				(font
					(size 1.27 1.27)
				)
			)
		)
		(duplicate_pad_numbers_are_jumpers no)
		(fp_poly
			(pts
				(xy -1.002101 0.504) (xy -1.002101 -0.503999) (xy 1.002101 -0.503999) (xy 1.002101 0.504)
			)
			(stroke
				(width 0)
				(type default)
			)
			(fill no)
			(layer "F.CrtYd")
		)
		(fp_line
			(start -0.499999 -0.249999)
			(end -0.499999 0.25)
			(stroke
				(width 0.1)
				(type default)
			)
			(layer "F.Fab")
		)
		(fp_line
			(start -0.499999 0.25)
			(end 0.499999 0.25)
			(stroke
				(width 0.1)
				(type default)
			)
			(layer "F.Fab")
		)
		(fp_line
			(start 0.499999 -0.249999)
			(end -0.499999 -0.249999)
			(stroke
				(width 0.1)
				(type default)
			)
			(layer "F.Fab")
		)
		(fp_line
			(start 0.499999 0.25)
			(end 0.499999 -0.249999)
			(stroke
				(width 0.1)
				(type default)
			)
			(layer "F.Fab")
		)
		(pad "1" smd rect
			(at -0.459999 0 90)
			(size 0.508 0.5842)
			(layers "F.Cu" "F.Mask" "F.Paste")
			(net "P3V3_B1_QSFP")
		)
		(pad "2" smd rect
			(at 0.459999 0 90)
			(size 0.508 0.5842)
			(layers "F.Cu" "F.Mask" "F.Paste")
			(net "UNNAMED_16_FERRITE_I115_A")
		)
	)
	(footprint ""
		(layer "F.Cu")
		(at -75.292801 5.270602 180)
		(property "Reference" "R49"
			(at -2.521801 0.025502 0)
			(unlocked yes)
			(layer "F.SilkS")
			(effects
				(font
					(size 0.762 0.5334)
					(thickness 0.1016)
				)
			)
		)
		(property "Value" ""
			(at 0 0 180)
			(layer "F.Fab")
			(effects
				(font
					(size 1.27 1.27)
				)
			)
		)
		(duplicate_pad_numbers_are_jumpers no)
		(fp_line
			(start 0 -0.381)
			(end 0 0.381)
			(stroke
				(width 0.127)
				(type default)
			)
			(layer "F.SilkS")
		)
		(fp_poly
			(pts
				(xy 1.255601 0.6564) (xy -1.255601 0.6564) (xy -1.255601 -0.656399) (xy 1.255601 -0.656399)
			)
			(stroke
				(width 0)
				(type default)
			)
			(fill no)
			(layer "F.CrtYd")
		)
		(fp_line
			(start 0.800001 0.4)
			(end 0.800001 -0.399999)
			(stroke
				(width 0.1)
				(type default)
			)
			(layer "F.Fab")
		)
		(fp_line
			(start 0.800001 -0.399999)
			(end -0.800001 -0.399999)
			(stroke
				(width 0.1)
				(type default)
			)
			(layer "F.Fab")
		)
		(fp_line
			(start -0.800001 0.4)
			(end 0.800001 0.4)
			(stroke
				(width 0.1)
				(type default)
			)
			(layer "F.Fab")
		)
		(fp_line
			(start -0.800001 -0.399999)
			(end -0.800001 0.4)
			(stroke
				(width 0.1)
				(type default)
			)
			(layer "F.Fab")
		)
		(pad "1" smd rect
			(at -0.650001 0 180)
			(size 0.7112 0.8128)
			(layers "F.Cu" "F.Mask" "F.Paste")
			(net "ETH10G_B2_TX_DIS")
		)
		(pad "2" smd rect
			(at 0.650001 0)
			(size 0.7112 0.8128)
			(layers "F.Cu" "F.Mask" "F.Paste")
			(net "GND")
		)
	)
	(footprint ""
		(layer "F.Cu")
		(at -300.951798 3.080601)
		(property "Reference" "R27"
			(at -3.340202 0.005499 0)
			(unlocked yes)
			(layer "F.SilkS")
			(effects
				(font
					(size 0.762 0.5334)
					(thickness 0.1016)
				)
			)
		)
		(property "Value" ""
			(at 0 0 0)
			(layer "F.Fab")
			(effects
				(font
					(size 1.27 1.27)
				)
			)
		)
		(duplicate_pad_numbers_are_jumpers no)
		(fp_line
			(start 0 -0.381)
			(end 0 0.381)
			(stroke
				(width 0.127)
				(type default)
			)
			(layer "F.SilkS")
		)
		(fp_poly
			(pts
				(xy 1.2556 0.656399) (xy -1.255601 0.656399) (xy -1.255601 -0.6564) (xy 1.2556 -0.6564)
			)
			(stroke
				(width 0)
				(type default)
			)
			(fill no)
			(layer "F.CrtYd")
		)
		(fp_line
			(start -0.800001 -0.399999)
			(end -0.800001 0.399999)
			(stroke
				(width 0.1)
				(type default)
			)
			(layer "F.Fab")
		)
		(fp_line
			(start -0.800001 0.399999)
			(end 0.800001 0.399999)
			(stroke
				(width 0.1)
				(type default)
			)
			(layer "F.Fab")
		)
		(fp_line
			(start 0.800001 -0.399999)
			(end -0.800001 -0.399999)
			(stroke
				(width 0.1)
				(type default)
			)
			(layer "F.Fab")
		)
		(fp_line
			(start 0.800001 0.399999)
			(end 0.800001 -0.399999)
			(stroke
				(width 0.1)
				(type default)
			)
			(layer "F.Fab")
		)
		(pad "1" smd rect
			(at -0.650001 0)
			(size 0.7112 0.8128)
			(layers "F.Cu" "F.Mask" "F.Paste")
			(net "P3V3_B1_QSFP")
		)
		(pad "2" smd rect
			(at 0.650001 0 180)
			(size 0.7112 0.8128)
			(layers "F.Cu" "F.Mask" "F.Paste")
			(net "ETH10G_B1_RX_LOS")
		)
	)
	(footprint ""
		(layer "F.Cu")
		(at -331.47 16.0528)
		(property "Reference" "R81"
			(at 3.175 -0.0127 0)
			(unlocked yes)
			(layer "F.SilkS")
			(effects
				(font
					(size 0.762 0.5334)
					(thickness 0.1016)
				)
			)
		)
		(property "Value" ""
			(at 0 0 0)
			(layer "F.Fab")
			(effects
				(font
					(size 1.27 1.27)
				)
			)
		)
		(duplicate_pad_numbers_are_jumpers no)
		(fp_line
			(start 0 -0.381)
			(end 0 0.381)
			(stroke
				(width 0.127)
				(type default)
			)
			(layer "F.SilkS")
		)
		(fp_poly
			(pts
				(xy 1.255601 0.6564) (xy -1.255601 0.6564) (xy -1.255601 -0.656399) (xy 1.255601 -0.656399)
			)
			(stroke
				(width 0)
				(type default)
			)
			(fill no)
			(layer "F.CrtYd")
		)
		(fp_line
			(start -0.800001 -0.399999)
			(end -0.800001 0.399999)
			(stroke
				(width 0.1)
				(type default)
			)
			(layer "F.Fab")
		)
		(fp_line
			(start -0.800001 0.399999)
			(end 0.800001 0.399999)
			(stroke
				(width 0.1)
				(type default)
			)
			(layer "F.Fab")
		)
		(fp_line
			(start 0.800001 -0.399999)
			(end -0.800001 -0.399999)
			(stroke
				(width 0.1)
				(type default)
			)
			(layer "F.Fab")
		)
		(fp_line
			(start 0.800001 0.399999)
			(end 0.800001 -0.399999)
			(stroke
				(width 0.1)
				(type default)
			)
			(layer "F.Fab")
		)
		(pad "1" smd rect
			(at -0.650001 0)
			(size 0.7112 0.8128)
			(layers "F.Cu" "F.Mask" "F.Paste")
			(net "P3V3_B1_QSFP")
		)
		(pad "2" smd rect
			(at 0.650001 0 180)
			(size 0.7112 0.8128)
			(layers "F.Cu" "F.Mask" "F.Paste")
			(net "ETH40G_B1_SDA")
		)
	)
	(footprint ""
		(layer "F.Cu")
		(at -165.770001 39.357399)
		(property "Reference" "MH4"
			(at 0 -4.9149 0)
			(unlocked yes)
			(layer "F.SilkS")
			(effects
				(font
					(size 0.762 0.5334)
					(thickness 0.1016)
				)
			)
		)
		(property "Value" ""
			(at 0 0 0)
			(layer "F.Fab")
			(effects
				(font
					(size 1.27 1.27)
				)
			)
		)
		(duplicate_pad_numbers_are_jumpers no)
		(fp_poly
			(pts
				(arc
					(start 4.0132 0)
					(mid -4.0132 0)
					(end 4.0132 0)
				)
			)
			(stroke
				(width 0)
				(type default)
			)
			(fill no)
			(layer "B.CrtYd")
		)
		(fp_poly
			(pts
				(arc
					(start 4.0132 0)
					(mid -4.0132 0)
					(end 4.0132 0)
				)
			)
			(stroke
				(width 0)
				(type default)
			)
			(fill no)
			(layer "F.CrtYd")
		)
		(pad "1" thru_hole circle
			(at 0 0)
			(size 7.0104 7.0104)
			(drill 3.5052)
			(layers "*.Cu" "*.Mask")
			(remove_unused_layers no)
			(net "GND")
			(padstack
				(mode front_inner_back)
				(layer "Inner"
					(shape circle)
					(size 4.5212 4.5212)
				)
				(layer "B.Cu"
					(shape circle)
					(size 7.0104 7.0104)
				)
			)
		)
		(pad "2" thru_hole circle
			(at 0 -2.794)
			(size 0.6604 0.6604)
			(drill 0.3556)
			(layers "*.Cu" "*.Mask")
			(remove_unused_layers no)
			(net "GND")
		)
		(pad "3" thru_hole circle
			(at -1.905 -2.032)
			(size 0.6604 0.6604)
			(drill 0.3556)
			(layers "*.Cu" "*.Mask")
			(remove_unused_layers no)
			(net "GND")
		)
		(pad "4" thru_hole circle
			(at -2.794 0)
			(size 0.6604 0.6604)
			(drill 0.3556)
			(layers "*.Cu" "*.Mask")
			(remove_unused_layers no)
			(net "GND")
		)
		(pad "5" thru_hole circle
			(at -2.032 1.905)
			(size 0.6604 0.6604)
			(drill 0.3556)
			(layers "*.Cu" "*.Mask")
			(remove_unused_layers no)
			(net "GND")
		)
		(pad "6" thru_hole circle
			(at 0 2.794)
			(size 0.6604 0.6604)
			(drill 0.3556)
			(layers "*.Cu" "*.Mask")
			(remove_unused_layers no)
			(net "GND")
		)
		(pad "7" thru_hole circle
			(at 2.032 1.905)
			(size 0.6604 0.6604)
			(drill 0.3556)
			(layers "*.Cu" "*.Mask")
			(remove_unused_layers no)
			(net "GND")
		)
		(pad "8" thru_hole circle
			(at 2.794 0)
			(size 0.6604 0.6604)
			(drill 0.3556)
			(layers "*.Cu" "*.Mask")
			(remove_unused_layers no)
			(net "GND")
		)
		(pad "9" thru_hole circle
			(at 1.905 -2.032)
			(size 0.6604 0.6604)
			(drill 0.3556)
			(layers "*.Cu" "*.Mask")
			(remove_unused_layers no)
			(net "GND")
		)
	)
	(footprint ""
		(layer "F.Cu")
		(at -266.109699 20.000001)
		(property "Reference" "MH3"
			(at -0.011181 -4.617761 0)
			(unlocked yes)
			(layer "F.SilkS")
			(effects
				(font
					(size 0.762 0.5334)
					(thickness 0.1016)
				)
			)
		)
		(property "Value" ""
			(at 0 0 0)
			(layer "F.Fab")
			(effects
				(font
					(size 1.27 1.27)
				)
			)
		)
		(duplicate_pad_numbers_are_jumpers no)
		(fp_poly
			(pts
				(arc
					(start 4.0132 0)
					(mid -4.0132 0)
					(end 4.0132 0)
				)
			)
			(stroke
				(width 0)
				(type default)
			)
			(fill no)
			(layer "B.CrtYd")
		)
		(fp_poly
			(pts
				(arc
					(start 4.0132 0)
					(mid -4.0132 0)
					(end 4.0132 0)
				)
			)
			(stroke
				(width 0)
				(type default)
			)
			(fill no)
			(layer "F.CrtYd")
		)
		(pad "1" thru_hole circle
			(at 0 0)
			(size 7.0104 7.0104)
			(drill 3.5052)
			(layers "*.Cu" "*.Mask")
			(remove_unused_layers no)
			(net "GND")
			(padstack
				(mode front_inner_back)
				(layer "Inner"
					(shape circle)
					(size 4.5212 4.5212)
				)
				(layer "B.Cu"
					(shape circle)
					(size 7.0104 7.0104)
				)
			)
		)
		(pad "2" thru_hole circle
			(at 0 -2.794)
			(size 0.6604 0.6604)
			(drill 0.3556)
			(layers "*.Cu" "*.Mask")
			(remove_unused_layers no)
			(net "GND")
		)
		(pad "3" thru_hole circle
			(at -1.905 -2.032)
			(size 0.6604 0.6604)
			(drill 0.3556)
			(layers "*.Cu" "*.Mask")
			(remove_unused_layers no)
			(net "GND")
		)
		(pad "4" thru_hole circle
			(at -2.794 0)
			(size 0.6604 0.6604)
			(drill 0.3556)
			(layers "*.Cu" "*.Mask")
			(remove_unused_layers no)
			(net "GND")
		)
		(pad "5" thru_hole circle
			(at -2.032 1.905)
			(size 0.6604 0.6604)
			(drill 0.3556)
			(layers "*.Cu" "*.Mask")
			(remove_unused_layers no)
			(net "GND")
		)
		(pad "6" thru_hole circle
			(at 0 2.794)
			(size 0.6604 0.6604)
			(drill 0.3556)
			(layers "*.Cu" "*.Mask")
			(remove_unused_layers no)
			(net "GND")
		)
		(pad "7" thru_hole circle
			(at 2.032 1.905)
			(size 0.6604 0.6604)
			(drill 0.3556)
			(layers "*.Cu" "*.Mask")
			(remove_unused_layers no)
			(net "GND")
		)
		(pad "8" thru_hole circle
			(at 2.794 0)
			(size 0.6604 0.6604)
			(drill 0.3556)
			(layers "*.Cu" "*.Mask")
			(remove_unused_layers no)
			(net "GND")
		)
		(pad "9" thru_hole circle
			(at 1.905 -2.032)
			(size 0.6604 0.6604)
			(drill 0.3556)
			(layers "*.Cu" "*.Mask")
			(remove_unused_layers no)
			(net "GND")
		)
	)
	(footprint ""
		(layer "F.Cu")
		(at -113.824601 21.145602 90)
		(property "Reference" "C13"
			(at -3.111398 -0.056299 90)
			(unlocked yes)
			(layer "F.SilkS")
			(effects
				(font
					(size 0.762 0.5334)
					(thickness 0.1016)
				)
			)
		)
		(property "Value" ""
			(at 0 0 90)
			(layer "F.Fab")
			(effects
				(font
					(size 1.27 1.27)
				)
			)
		)
		(duplicate_pad_numbers_are_jumpers no)
		(fp_line
			(start 0 -0.381)
			(end 0 0.381)
			(stroke
				(width 0.127)
				(type default)
			)
			(layer "F.SilkS")
		)
		(fp_poly
			(pts
				(xy 1.2533 0.6564) (xy -1.253299 0.6564) (xy -1.253299 -0.656399) (xy 1.2533 -0.656399)
			)
			(stroke
				(width 0)
				(type default)
			)
			(fill no)
			(layer "F.CrtYd")
		)
		(fp_line
			(start 0.762 -0.381)
			(end -0.762 -0.381)
			(stroke
				(width 0.1)
				(type default)
			)
			(layer "F.Fab")
		)
		(fp_line
			(start -0.762 -0.381)
			(end -0.762 0.381)
			(stroke
				(width 0.1)
				(type default)
			)
			(layer "F.Fab")
		)
		(fp_line
			(start 0.762 0.381)
			(end 0.762 -0.381)
			(stroke
				(width 0.1)
				(type default)
			)
			(layer "F.Fab")
		)
		(fp_line
			(start -0.762 0.381)
			(end 0.762 0.381)
			(stroke
				(width 0.1)
				(type default)
			)
			(layer "F.Fab")
		)
		(pad "1" smd rect
			(at -0.6477 0 90)
			(size 0.7112 0.8128)
			(layers "F.Cu" "F.Mask" "F.Paste")
			(net "P12V")
		)
		(pad "2" smd rect
			(at 0.6477 0 270)
			(size 0.7112 0.8128)
			(layers "F.Cu" "F.Mask" "F.Paste")
			(net "GND")
		)
	)
	(footprint ""
		(layer "F.Cu")
		(at -44.7802 4.191 180)
		(property "Reference" "C27"
			(at -2.97434 -0.5715 0)
			(unlocked yes)
			(layer "F.SilkS")
			(effects
				(font
					(size 0.762 0.5334)
					(thickness 0.1016)
				)
			)
		)
		(property "Value" ""
			(at 0 0 180)
			(layer "F.Fab")
			(effects
				(font
					(size 1.27 1.27)
				)
			)
		)
		(duplicate_pad_numbers_are_jumpers no)
		(fp_line
			(start 0 -0.381)
			(end 0 0.381)
			(stroke
				(width 0.127)
				(type default)
			)
			(layer "F.SilkS")
		)
		(fp_poly
			(pts
				(xy 1.2533 0.656399) (xy -1.253299 0.656399) (xy -1.253299 -0.6564) (xy 1.2533 -0.6564)
			)
			(stroke
				(width 0)
				(type default)
			)
			(fill no)
			(layer "F.CrtYd")
		)
		(fp_line
			(start 0.762 0.381)
			(end 0.762 -0.381)
			(stroke
				(width 0.1)
				(type default)
			)
			(layer "F.Fab")
		)
		(fp_line
			(start 0.762 -0.381)
			(end -0.762 -0.381)
			(stroke
				(width 0.1)
				(type default)
			)
			(layer "F.Fab")
		)
		(fp_line
			(start -0.762 0.381)
			(end 0.762 0.381)
			(stroke
				(width 0.1)
				(type default)
			)
			(layer "F.Fab")
		)
		(fp_line
			(start -0.762 -0.381)
			(end -0.762 0.381)
			(stroke
				(width 0.1)
				(type default)
			)
			(layer "F.Fab")
		)
		(pad "1" smd rect
			(at -0.6477 0 180)
			(size 0.7112 0.8128)
			(layers "F.Cu" "F.Mask" "F.Paste")
			(net "P3V3_B2_QSFP")
		)
		(pad "2" smd rect
			(at 0.6477 0)
			(size 0.7112 0.8128)
			(layers "F.Cu" "F.Mask" "F.Paste")
			(net "GND")
		)
	)
	(footprint ""
		(layer "F.Cu")
		(at -354.6094 34.0614 90)
		(property "Reference" "C2"
			(at -2.159 -0.0889 90)
			(unlocked yes)
			(layer "F.SilkS")
			(effects
				(font
					(size 0.762 0.5334)
					(thickness 0.1016)
				)
			)
		)
		(property "Value" ""
			(at 0 0 90)
			(layer "F.Fab")
			(effects
				(font
					(size 1.27 1.27)
				)
			)
		)
		(duplicate_pad_numbers_are_jumpers no)
		(fp_line
			(start 0 -0.381)
			(end 0 0.381)
			(stroke
				(width 0.127)
				(type default)
			)
			(layer "F.SilkS")
		)
		(fp_poly
			(pts
				(xy 1.253299 0.656399) (xy -1.2533 0.656399) (xy -1.2533 -0.6564) (xy 1.253299 -0.6564)
			)
			(stroke
				(width 0)
				(type default)
			)
			(fill no)
			(layer "F.CrtYd")
		)
		(fp_line
			(start 0.762 -0.381)
			(end -0.762 -0.381)
			(stroke
				(width 0.1)
				(type default)
			)
			(layer "F.Fab")
		)
		(fp_line
			(start -0.762 -0.381)
			(end -0.762 0.381)
			(stroke
				(width 0.1)
				(type default)
			)
			(layer "F.Fab")
		)
		(fp_line
			(start 0.762 0.381)
			(end 0.762 -0.381)
			(stroke
				(width 0.1)
				(type default)
			)
			(layer "F.Fab")
		)
		(fp_line
			(start -0.762 0.381)
			(end 0.762 0.381)
			(stroke
				(width 0.1)
				(type default)
			)
			(layer "F.Fab")
		)
		(pad "1" smd rect
			(at -0.6477 0 90)
			(size 0.7112 0.8128)
			(layers "F.Cu" "F.Mask" "F.Paste")
			(net "P12V")
		)
		(pad "2" smd rect
			(at 0.6477 0 270)
			(size 0.7112 0.8128)
			(layers "F.Cu" "F.Mask" "F.Paste")
			(net "GND")
		)
	)
)
